(kicad_pcb
	(version 20241229)
	(generator "pcbnew")
	(generator_version "9.0")
	(general
		(thickness 1.62)
		(legacy_teardrops no)
	)
	(paper "A3")
	(title_block
		(title "COM Express 7 Baseboard")
		(date "2025-02-04")
		(rev "1.1.2")
		(company "Antmicro Ltd")
		(comment 1 "www.antmicro.com")
		(comment 9 "footprints 469-473 of 802")
	)
	(layers
		(0 "F.Cu" signal)
		(4 "In1.Cu" signal)
		(6 "In2.Cu" signal)
		(8 "In3.Cu" signal)
		(10 "In4.Cu" signal)
		(12 "In5.Cu" signal)
		(14 "In6.Cu" signal)
		(2 "B.Cu" signal)
		(9 "F.Adhes" user "F.Adhesive")
		(11 "B.Adhes" user "B.Adhesive")
		(13 "F.Paste" user)
		(15 "B.Paste" user)
		(5 "F.SilkS" user "F.Silkscreen")
		(7 "B.SilkS" user "B.Silkscreen")
		(1 "F.Mask" user)
		(3 "B.Mask" user)
		(17 "Dwgs.User" user "User.Drawings")
		(19 "Cmts.User" user "User.Comments")
		(21 "Eco1.User" user "User.Eco1")
		(23 "Eco2.User" user "User.Eco2")
		(25 "Edge.Cuts" user)
		(27 "Margin" user)
		(31 "F.CrtYd" user "F.Courtyard")
		(29 "B.CrtYd" user "B.Courtyard")
		(35 "F.Fab" user)
		(33 "B.Fab" user)
	)
	(footprint "antmicro-footprints:LED_0603_1608Metric_G"
		(layer "F.Cu")
		(at 116.45 69.86 90)
		(descr "LED SMD 0603 Green")
		(tags "LED SMD 0603 Green")
		(property "Reference" "D15"
			(at -3.35 0.4 90)
			(layer "F.SilkS")
			(effects
				(font
					(size 0.7 0.7)
					(thickness 0.15)
				)
				(justify left bottom)
			)
		)
		(property "Value" "LED_G_0603_LTST-C190GKT"
			(at -0.001 1.599 90)
			(layer "F.Fab")
			(effects
				(font
					(size 0.7 0.7)
					(thickness 0.15)
				)
				(justify left bottom)
			)
		)
		(property "Datasheet" "https://media.digikey.com/pdf/Data%20Sheets/Lite-On%20PDFs/LTST-C190GKT.pdf"
			(at 0 0 90)
			(layer "F.Fab")
			(hide yes)
			(effects
				(font
					(size 1.27 1.27)
					(thickness 0.15)
				)
			)
		)
		(property "Author" "Antmicro"
			(at 186.31 -46.59 0)
			(layer "F.Fab")
			(hide yes)
			(effects
				(font
					(size 1 1)
					(thickness 0.15)
				)
			)
		)
		(property "Color" "Green"
			(at 186.31 -46.59 0)
			(layer "F.Fab")
			(hide yes)
			(effects
				(font
					(size 1 1)
					(thickness 0.15)
				)
			)
		)
		(property "License" "Apache-2.0"
			(at 186.31 -46.59 0)
			(layer "F.Fab")
			(hide yes)
			(effects
				(font
					(size 1 1)
					(thickness 0.15)
				)
			)
		)
		(property "MPN" "LTST-C190GKT"
			(at 186.31 -46.59 0)
			(layer "F.Fab")
			(hide yes)
			(effects
				(font
					(size 1 1)
					(thickness 0.15)
				)
			)
		)
		(property "Manufacturer" "Lite-On"
			(at 186.31 -46.59 0)
			(layer "F.Fab")
			(hide yes)
			(effects
				(font
					(size 1 1)
					(thickness 0.15)
				)
			)
		)
		(property "Public" "False"
			(at 186.31 -46.59 0)
			(layer "F.Fab")
			(hide yes)
			(effects
				(font
					(size 1 1)
					(thickness 0.15)
				)
			)
		)
		(sheetname "M.2 key E")
		(sheetfile "m2keye.kicad_sch")
		(attr smd)
		(fp_line
			(start 0.22 -0.35)
			(end -0.22 -0.35)
			(stroke
				(width 0.15)
				(type solid)
			)
			(layer "F.SilkS")
		)
		(fp_line
			(start -1.18 -0.319)
			(end -1.18 0.321)
			(stroke
				(width 0.15)
				(type solid)
			)
			(layer "F.SilkS")
		)
		(fp_line
			(start 0.105328 0.001008)
			(end 0.24 0.001)
			(stroke
				(width 0.1)
				(type solid)
			)
			(layer "F.SilkS")
		)
		(fp_line
			(start -0.094672 0.001008)
			(end 0.105328 -0.198992)
			(stroke
				(width 0.1)
				(type solid)
			)
			(layer "F.SilkS")
		)
		(fp_line
			(start -0.094672 0.001008)
			(end -0.24 0.001008)
			(stroke
				(width 0.1)
				(type solid)
			)
			(layer "F.SilkS")
		)
		(fp_line
			(start 0.105328 0.201008)
			(end 0.105328 -0.198992)
			(stroke
				(width 0.1)
				(type solid)
			)
			(layer "F.SilkS")
		)
		(fp_line
			(start 0.105328 0.201008)
			(end -0.094672 0.001008)
			(stroke
				(width 0.1)
				(type solid)
			)
			(layer "F.SilkS")
		)
		(fp_line
			(start -0.094672 0.201008)
			(end -0.094672 -0.198992)
			(stroke
				(width 0.1)
				(type solid)
			)
			(layer "F.SilkS")
		)
		(fp_line
			(start 0.22 0.35)
			(end -0.22 0.35)
			(stroke
				(width 0.15)
				(type solid)
			)
			(layer "F.SilkS")
		)
		(fp_rect
			(start 1.25 0.65)
			(end -1.25 -0.65)
			(stroke
				(width 0.05)
				(type solid)
			)
			(fill no)
			(layer "F.CrtYd")
		)
		(fp_line
			(start 0.201 -0.202)
			(end -0.101 0)
			(stroke
				(width 0.15)
				(type solid)
			)
			(layer "F.Fab")
		)
		(fp_line
			(start -0.199 -0.202)
			(end -0.199 0.1)
			(stroke
				(width 0.15)
				(type solid)
			)
			(layer "F.Fab")
		)
		(fp_line
			(start 0.599 0)
			(end 0.201 0)
			(stroke
				(width 0.15)
				(type solid)
			)
			(layer "F.Fab")
		)
		(fp_line
			(start 0.201 0)
			(end 0.201 -0.202)
			(stroke
				(width 0.15)
				(type solid)
			)
			(layer "F.Fab")
		)
		(fp_line
			(start -0.101 0)
			(end 0.201 0.2)
			(stroke
				(width 0.15)
				(type solid)
			)
			(layer "F.Fab")
		)
		(fp_line
			(start -0.199 0)
			(end -0.597 0)
			(stroke
				(width 0.15)
				(type solid)
			)
			(layer "F.Fab")
		)
		(fp_line
			(start 0.201 0.2)
			(end 0.201 0)
			(stroke
				(width 0.15)
				(type solid)
			)
			(layer "F.Fab")
		)
		(fp_line
			(start -0.199 0.2)
			(end -0.199 0.1)
			(stroke
				(width 0.15)
				(type solid)
			)
			(layer "F.Fab")
		)
		(fp_rect
			(start 0.848 0.4)
			(end -0.85 -0.402)
			(stroke
				(width 0.15)
				(type solid)
			)
			(fill no)
			(layer "F.Fab")
		)
		(pad "1" smd roundrect
			(at -0.7 0 270)
			(size 0.8 1)
			(layers "F.Cu" "F.Mask" "F.Paste")
			(roundrect_rratio 0.2)
			(net 5 "/M.2 key E/~{LED_1}")
			(pinfunction "C")
			(pintype "passive")
			(teardrops
				(best_length_ratio 0.2)
				(max_length 1)
				(best_width_ratio 0.9)
				(max_width 2)
				(curved_edges yes)
				(filter_ratio 0.9)
				(enabled yes)
				(allow_two_segments yes)
				(prefer_zone_connections yes)
			)
		)
		(pad "2" smd roundrect
			(at 0.7 0 270)
			(size 0.8 1)
			(layers "F.Cu" "F.Mask" "F.Paste")
			(roundrect_rratio 0.2)
			(net 937 "Net-(D15-A)")
			(pinfunction "A")
			(pintype "passive")
			(teardrops
				(best_length_ratio 0.2)
				(max_length 1)
				(best_width_ratio 0.9)
				(max_width 2)
				(curved_edges yes)
				(filter_ratio 0.9)
				(enabled yes)
				(allow_two_segments yes)
				(prefer_zone_connections yes)
			)
		)
	)
	(footprint "antmicro-footprints:R_0402_1005Metric"
		(layer "F.Cu")
		(at 313.765499 97.4365 -90)
		(descr "Resistor SMD 0402")
		(tags "resistor SMD 0402")
		(property "Reference" "R109"
			(at -10.1265 -4.734501 90)
			(layer "F.SilkS")
			(effects
				(font
					(size 0.7 0.7)
					(thickness 0.15)
				)
				(justify right bottom)
			)
		)
		(property "Value" "R_110k_0402"
			(at -1.011843 1.772047 90)
			(layer "F.Fab")
			(effects
				(font
					(size 0.7 0.7)
					(thickness 0.15)
				)
				(justify right bottom)
			)
		)
		(property "Datasheet" "https://www.bourns.com/docs/product-datasheets/cr.pdf"
			(at 0 0 270)
			(layer "F.Fab")
			(hide yes)
			(effects
				(font
					(size 1.27 1.27)
					(thickness 0.15)
				)
			)
		)
		(property "Author" "Antmicro"
			(at 216.328999 411.201999 0)
			(layer "F.Fab")
			(hide yes)
			(effects
				(font
					(size 1 1)
					(thickness 0.15)
				)
			)
		)
		(property "License" "Apache-2.0"
			(at 216.328999 411.201999 0)
			(layer "F.Fab")
			(hide yes)
			(effects
				(font
					(size 1 1)
					(thickness 0.15)
				)
			)
		)
		(property "MPN" "CR0402-FX-1103GLF"
			(at 216.328999 411.201999 0)
			(layer "F.Fab")
			(hide yes)
			(effects
				(font
					(size 1 1)
					(thickness 0.15)
				)
			)
		)
		(property "Manufacturer" "Bourns"
			(at 216.328999 411.201999 0)
			(layer "F.Fab")
			(hide yes)
			(effects
				(font
					(size 1 1)
					(thickness 0.15)
				)
			)
		)
		(property "Public" "False"
			(at 216.328999 411.201999 0)
			(layer "F.Fab")
			(hide yes)
			(effects
				(font
					(size 1 1)
					(thickness 0.15)
				)
			)
		)
		(property "Tolerance" "1%"
			(at 216.328999 411.201999 0)
			(layer "F.Fab")
			(hide yes)
			(effects
				(font
					(size 1 1)
					(thickness 0.15)
				)
			)
		)
		(property "Val" "110k"
			(at 216.328999 411.201999 0)
			(layer "F.Fab")
			(hide yes)
			(effects
				(font
					(size 1 1)
					(thickness 0.15)
				)
			)
		)
		(sheetname "Power")
		(sheetfile "power.kicad_sch")
		(attr smd)
		(fp_rect
			(start -0.925 -0.47)
			(end 0.925 0.47)
			(stroke
				(width 0.05)
				(type default)
			)
			(fill no)
			(layer "F.CrtYd")
		)
		(fp_rect
			(start -0.5 -0.25)
			(end 0.5 0.25)
			(stroke
				(width 0.15)
				(type solid)
			)
			(fill no)
			(layer "F.Fab")
		)
		(pad "1" smd roundrect
			(at -0.48 0 270)
			(size 0.59 0.64)
			(layers "F.Cu" "F.Mask" "F.Paste")
			(roundrect_rratio 0.25)
			(net 585 "Net-(U21-FB)")
			(pintype "passive")
			(teardrops
				(best_length_ratio 0.2)
				(max_length 1)
				(best_width_ratio 0.9)
				(max_width 2)
				(curved_edges yes)
				(filter_ratio 0.9)
				(enabled yes)
				(allow_two_segments yes)
				(prefer_zone_connections yes)
			)
		)
		(pad "2" smd roundrect
			(at 0.48 0 270)
			(size 0.59 0.64)
			(layers "F.Cu" "F.Mask" "F.Paste")
			(roundrect_rratio 0.25)
			(net 75 "Net-(U50-IN+)")
			(pintype "passive")
			(teardrops
				(best_length_ratio 0.2)
				(max_length 1)
				(best_width_ratio 0.9)
				(max_width 2)
				(curved_edges yes)
				(filter_ratio 0.9)
				(enabled yes)
				(allow_two_segments yes)
				(prefer_zone_connections yes)
			)
		)
	)
	(footprint "antmicro-footprints:C_0402_1005Metric"
		(layer "F.Cu")
		(at 300.55 137.41 90)
		(descr "Capacitor SMD 0402")
		(tags "capacitor SMD 0402")
		(property "Reference" "C68"
			(at -1.1 -0.5 90)
			(layer "F.SilkS")
			(effects
				(font
					(size 0.7 0.7)
					(thickness 0.15)
				)
				(justify left bottom)
			)
		)
		(property "Value" "C_1u_0402"
			(at -1.022927 2.155213 90)
			(layer "F.Fab")
			(effects
				(font
					(size 0.7 0.7)
					(thickness 0.15)
				)
				(justify left bottom)
			)
		)
		(property "Datasheet" "https://product.tdk.com/en/search/capacitor/ceramic/mlcc/info?part_no=C1005X6S1A105K050BC"
			(at 0 0 90)
			(layer "F.Fab")
			(hide yes)
			(effects
				(font
					(size 1.27 1.27)
					(thickness 0.15)
				)
			)
		)
		(property "Author" "Antmicro"
			(at 437.96 -163.14 0)
			(layer "F.Fab")
			(hide yes)
			(effects
				(font
					(size 1 1)
					(thickness 0.15)
				)
			)
		)
		(property "Dielectric" ""
			(at 437.96 -163.14 0)
			(layer "F.Fab")
			(hide yes)
			(effects
				(font
					(size 1 1)
					(thickness 0.15)
				)
			)
		)
		(property "License" "Apache-2.0"
			(at 437.96 -163.14 0)
			(layer "F.Fab")
			(hide yes)
			(effects
				(font
					(size 1 1)
					(thickness 0.15)
				)
			)
		)
		(property "MPN" "C1005X6S1A105K050BC"
			(at 437.96 -163.14 0)
			(layer "F.Fab")
			(hide yes)
			(effects
				(font
					(size 1 1)
					(thickness 0.15)
				)
			)
		)
		(property "Manufacturer" "TDK"
			(at 437.96 -163.14 0)
			(layer "F.Fab")
			(hide yes)
			(effects
				(font
					(size 1 1)
					(thickness 0.15)
				)
			)
		)
		(property "Public" "False"
			(at 437.96 -163.14 0)
			(layer "F.Fab")
			(hide yes)
			(effects
				(font
					(size 1 1)
					(thickness 0.15)
				)
			)
		)
		(property "Val" "1u"
			(at 437.96 -163.14 0)
			(layer "F.Fab")
			(hide yes)
			(effects
				(font
					(size 1 1)
					(thickness 0.15)
				)
			)
		)
		(property "Voltage" ""
			(at 437.96 -163.14 0)
			(layer "F.Fab")
			(hide yes)
			(effects
				(font
					(size 1 1)
					(thickness 0.15)
				)
			)
		)
		(sheetname "Power")
		(sheetfile "power.kicad_sch")
		(attr smd)
		(fp_rect
			(start -0.925 -0.47)
			(end 0.925 0.47)
			(stroke
				(width 0.05)
				(type default)
			)
			(fill no)
			(layer "F.CrtYd")
		)
		(fp_line
			(start 0.504 -0.25)
			(end 0.504 0.248)
			(stroke
				(width 0.15)
				(type solid)
			)
			(layer "F.Fab")
		)
		(fp_line
			(start -0.494 -0.25)
			(end 0.504 -0.25)
			(stroke
				(width 0.15)
				(type solid)
			)
			(layer "F.Fab")
		)
		(fp_line
			(start 0.504 0.248)
			(end -0.494 0.248)
			(stroke
				(width 0.15)
				(type solid)
			)
			(layer "F.Fab")
		)
		(fp_line
			(start -0.494 0.248)
			(end -0.494 -0.25)
			(stroke
				(width 0.15)
				(type solid)
			)
			(layer "F.Fab")
		)
		(pad "1" smd roundrect
			(at -0.48 0 90)
			(size 0.59 0.64)
			(layers "F.Cu" "F.Mask" "F.Paste")
			(roundrect_rratio 0.25)
			(net 1 "GND")
			(pintype "passive")
			(teardrops
				(best_length_ratio 0.2)
				(max_length 1)
				(best_width_ratio 0.9)
				(max_width 2)
				(curved_edges yes)
				(filter_ratio 0.9)
				(enabled yes)
				(allow_two_segments yes)
				(prefer_zone_connections yes)
			)
		)
		(pad "2" smd roundrect
			(at 0.48 0 90)
			(size 0.59 0.64)
			(layers "F.Cu" "F.Mask" "F.Paste")
			(roundrect_rratio 0.25)
			(net 78 "+1V8")
			(pintype "passive")
			(teardrops
				(best_length_ratio 0.2)
				(max_length 1)
				(best_width_ratio 0.9)
				(max_width 2)
				(curved_edges yes)
				(filter_ratio 0.9)
				(enabled yes)
				(allow_two_segments yes)
				(prefer_zone_connections yes)
			)
		)
	)
	(footprint "antmicro-footprints:R_0402_1005Metric"
		(layer "F.Cu")
		(at 130.08 115.6 180)
		(descr "Resistor SMD 0402")
		(tags "resistor SMD 0402")
		(property "Reference" "R23"
			(at 0.780999 0.45 0)
			(layer "F.SilkS")
			(effects
				(font
					(size 0.7 0.7)
					(thickness 0.15)
				)
				(justify right top)
			)
		)
		(property "Value" "R_0R_0402"
			(at -1.011843 1.772046 0)
			(layer "F.Fab")
			(effects
				(font
					(size 0.7 0.7)
					(thickness 0.15)
				)
				(justify right top)
			)
		)
		(property "Datasheet" "https://industrial.panasonic.com/cdbs/www-data/pdf/RDA0000/AOA0000C301.pdf"
			(at 0 0 0)
			(layer "F.Fab")
			(hide yes)
			(effects
				(font
					(size 1.27 1.27)
					(thickness 0.15)
				)
			)
		)
		(property "Author" "Antmicro"
			(at 355.241 -59.058999 90)
			(layer "F.Fab")
			(hide yes)
			(effects
				(font
					(size 1 1)
					(thickness 0.15)
				)
			)
		)
		(property "Current" "1A"
			(at 355.241 -59.058999 90)
			(layer "F.Fab")
			(hide yes)
			(effects
				(font
					(size 1 1)
					(thickness 0.15)
				)
			)
		)
		(property "License" "Apache-2.0"
			(at 355.241 -59.058999 90)
			(layer "F.Fab")
			(hide yes)
			(effects
				(font
					(size 1 1)
					(thickness 0.15)
				)
			)
		)
		(property "MPN" "ERJ2GE0R00X"
			(at 355.241 -59.058999 90)
			(layer "F.Fab")
			(hide yes)
			(effects
				(font
					(size 1 1)
					(thickness 0.15)
				)
			)
		)
		(property "Manufacturer" "Panasonic"
			(at 355.241 -59.058999 90)
			(layer "F.Fab")
			(hide yes)
			(effects
				(font
					(size 1 1)
					(thickness 0.15)
				)
			)
		)
		(property "Public" "False"
			(at 355.241 -59.058999 90)
			(layer "F.Fab")
			(hide yes)
			(effects
				(font
					(size 1 1)
					(thickness 0.15)
				)
			)
		)
		(property "Tolerance" ""
			(at 355.241 -59.058999 90)
			(layer "F.Fab")
			(hide yes)
			(effects
				(font
					(size 1 1)
					(thickness 0.15)
				)
			)
		)
		(property "Val" "0R"
			(at 355.241 -59.058999 90)
			(layer "F.Fab")
			(hide yes)
			(effects
				(font
					(size 1 1)
					(thickness 0.15)
				)
			)
		)
		(sheetname "2xUSB3.0+RJ45")
		(sheetfile "usb3+rj45.kicad_sch")
		(attr smd)
		(fp_rect
			(start -0.925 -0.47)
			(end 0.925 0.47)
			(stroke
				(width 0.05)
				(type default)
			)
			(fill no)
			(layer "F.CrtYd")
		)
		(fp_rect
			(start -0.5 -0.25)
			(end 0.5 0.25)
			(stroke
				(width 0.15)
				(type solid)
			)
			(fill no)
			(layer "F.Fab")
		)
		(pad "1" smd roundrect
			(at -0.48 0 180)
			(size 0.59 0.64)
			(layers "F.Cu" "F.Mask" "F.Paste")
			(roundrect_rratio 0.25)
			(net 374 "/2xUSB3.0+RJ45/USB_2.D-")
			(pintype "passive")
			(teardrops
				(best_length_ratio 0.2)
				(max_length 1)
				(best_width_ratio 0.9)
				(max_width 2)
				(curved_edges yes)
				(filter_ratio 0.9)
				(enabled yes)
				(allow_two_segments yes)
				(prefer_zone_connections yes)
			)
		)
		(pad "2" smd roundrect
			(at 0.48 0 180)
			(size 0.59 0.64)
			(layers "F.Cu" "F.Mask" "F.Paste")
			(roundrect_rratio 0.25)
			(net 125 "/2xUSB3.0+RJ45/P2_D-")
			(pintype "passive")
			(teardrops
				(best_length_ratio 0.2)
				(max_length 1)
				(best_width_ratio 0.9)
				(max_width 2)
				(curved_edges yes)
				(filter_ratio 0.9)
				(enabled yes)
				(allow_two_segments yes)
				(prefer_zone_connections yes)
			)
		)
	)
	(footprint "antmicro-footprints:R_0402_1005Metric"
		(layer "F.Cu")
		(at 245.8 132.353999 -90)
		(descr "Resistor SMD 0402")
		(tags "resistor SMD 0402")
		(property "Reference" "R174"
			(at 0.856001 -0.4 90)
			(layer "F.SilkS")
			(effects
				(font
					(size 0.7 0.7)
					(thickness 0.15)
				)
				(justify right bottom)
			)
		)
		(property "Value" "R_0R_0402"
			(at -1.011843 1.772047 90)
			(layer "F.Fab")
			(effects
				(font
					(size 0.7 0.7)
					(thickness 0.15)
				)
				(justify right bottom)
			)
		)
		(property "Datasheet" "https://industrial.panasonic.com/cdbs/www-data/pdf/RDA0000/AOA0000C301.pdf"
			(at 0 0 270)
			(layer "F.Fab")
			(hide yes)
			(effects
				(font
					(size 1.27 1.27)
					(thickness 0.15)
				)
			)
		)
		(property "Author" "Antmicro"
			(at 113.446001 378.153999 0)
			(layer "F.Fab")
			(hide yes)
			(effects
				(font
					(size 1 1)
					(thickness 0.15)
				)
			)
		)
		(property "Current" "1A"
			(at 113.446001 378.153999 0)
			(layer "F.Fab")
			(hide yes)
			(effects
				(font
					(size 1 1)
					(thickness 0.15)
				)
			)
		)
		(property "License" "Apache-2.0"
			(at 113.446001 378.153999 0)
			(layer "F.Fab")
			(hide yes)
			(effects
				(font
					(size 1 1)
					(thickness 0.15)
				)
			)
		)
		(property "MPN" "ERJ2GE0R00X"
			(at 113.446001 378.153999 0)
			(layer "F.Fab")
			(hide yes)
			(effects
				(font
					(size 1 1)
					(thickness 0.15)
				)
			)
		)
		(property "Manufacturer" "Panasonic"
			(at 113.446001 378.153999 0)
			(layer "F.Fab")
			(hide yes)
			(effects
				(font
					(size 1 1)
					(thickness 0.15)
				)
			)
		)
		(property "Public" "False"
			(at 113.446001 378.153999 0)
			(layer "F.Fab")
			(hide yes)
			(effects
				(font
					(size 1 1)
					(thickness 0.15)
				)
			)
		)
		(property "Tolerance" ""
			(at 113.446001 378.153999 0)
			(layer "F.Fab")
			(hide yes)
			(effects
				(font
					(size 1 1)
					(thickness 0.15)
				)
			)
		)
		(property "Val" "0R"
			(at 113.446001 378.153999 0)
			(layer "F.Fab")
			(hide yes)
			(effects
				(font
					(size 1 1)
					(thickness 0.15)
				)
			)
		)
		(sheetname "Com Express 7 MGMT")
		(sheetfile "com_express_7_mgmt.kicad_sch")
		(attr smd)
		(fp_rect
			(start -0.925 -0.47)
			(end 0.925 0.47)
			(stroke
				(width 0.05)
				(type default)
			)
			(fill no)
			(layer "F.CrtYd")
		)
		(fp_rect
			(start -0.5 -0.25)
			(end 0.5 0.25)
			(stroke
				(width 0.15)
				(type solid)
			)
			(fill no)
			(layer "F.Fab")
		)
		(pad "1" smd roundrect
			(at -0.48 0 270)
			(size 0.59 0.64)
			(layers "F.Cu" "F.Mask" "F.Paste")
			(roundrect_rratio 0.25)
			(net 872 "Net-(U34-~{KILL})")
			(pintype "passive")
			(teardrops
				(best_length_ratio 0.2)
				(max_length 1)
				(best_width_ratio 0.9)
				(max_width 2)
				(curved_edges yes)
				(filter_ratio 0.9)
				(enabled yes)
				(allow_two_segments yes)
				(prefer_zone_connections yes)
			)
		)
		(pad "2" smd roundrect
			(at 0.48 0 270)
			(size 0.59 0.64)
			(layers "F.Cu" "F.Mask" "F.Paste")
			(roundrect_rratio 0.25)
			(net 303 "/Com Express 7 MGMT/~{SUS_S5}")
			(pintype "passive")
			(teardrops
				(best_length_ratio 0.2)
				(max_length 1)
				(best_width_ratio 0.9)
				(max_width 2)
				(curved_edges yes)
				(filter_ratio 0.9)
				(enabled yes)
				(allow_two_segments yes)
				(prefer_zone_connections yes)
			)
		)
	)
)
